# BASEBOARD_FAB2 (Tioga Pass) — schematic netlist excerpt (pin names and nets, part order shuffled) for the footprints in the layout excerpt that follows; sources: Cadence DE-HDL packaged netlist, KiCad conversion of Wiwynn_Tioga_Pass_MB.brd

R9P33  RES  100.0K 1% CHIP  pkg 0402  page 200 : A = P12V_STBY ; B = A_HSC_INAP
C1R4  CAP  0.22UF 16V 10% X7R  pkg 0402  page 106 : A = P3E_CPU0_PE3_OCP_TXP<1> ; B = P3E_OCP_CPU0_PE3_C_TXP<1>
C5L2  CAP  100UF 4V 20% X5R  pkg 0805  page 220 : A = PVDDQ_DEF ; B = GND

(kicad_pcb
	(version 20260206)
	(generator "pcbnew")
	(generator_version "10.0")
	(general
		(thickness 1.6)
		(legacy_teardrops no)
	)
	(paper "A4")
	(title_block
		(title "Wiwynn_Tioga_Pass_MB.brd")
		(comment 1 "Tioga Pass / footprints 4223-4225 of 4770")
	)
	(layers
		(0 "F.Cu" signal "TOP")
		(4 "In1.Cu" signal "L2GND")
		(6 "In2.Cu" signal "L3")
		(8 "In3.Cu" signal "L4GND")
		(10 "In4.Cu" signal "L5")
		(12 "In5.Cu" signal "L6GND")
		(14 "In6.Cu" signal "L7VCC")
		(16 "In7.Cu" signal "L8VCC")
		(18 "In8.Cu" signal "L9GND")
		(20 "In9.Cu" signal "L10")
		(22 "In10.Cu" signal "L11GND")
		(24 "In11.Cu" signal "L12")
		(26 "In12.Cu" signal "L13GND")
		(2 "B.Cu" signal "BOTTOM")
		(9 "F.Adhes" user "F.Adhesive")
		(11 "B.Adhes" user "B.Adhesive")
		(13 "F.Paste" user "Package Geometry/Pastemask Top")
		(15 "B.Paste" user "Package Geometry/Pastemask Bottom")
		(5 "F.SilkS" user "Ref Des/Silkscreen Top")
		(7 "B.SilkS" user "Ref Des/Silkscreen Bottom")
		(1 "F.Mask" user "Board Geometry/Soldermask Top")
		(3 "B.Mask" user "Board Geometry/Soldermask Bottom")
		(17 "Dwgs.User" user "User.Drawings")
		(19 "Cmts.User" user "User.Comments")
		(21 "Eco1.User" user "User.Eco1")
		(23 "Eco2.User" user "User.Eco2")
		(25 "Edge.Cuts" user "Board Geometry/Outline")
		(27 "Margin" user)
		(31 "F.CrtYd" user "Package Geometry/Place Bound Top")
		(29 "B.CrtYd" user "Package Geometry/Place Bound Bottom")
		(35 "F.Fab" user "Ref Des/Assembly Top")
		(33 "B.Fab" user "Ref Des/Assembly Bottom")
	)
	(footprint ""
		(layer "B.Cu")
		(at 272.931128 -156.960824 90)
		(property "Reference" "C5L2"
			(at 0 0 90)
			(layer "B.SilkS")
			(hide yes)
			(effects
				(font
					(size 1.27 1.27)
				)
				(justify mirror)
			)
		)
		(property "Value" ""
			(at 0 0 90)
			(layer "B.Fab")
			(effects
				(font
					(size 1.27 1.27)
				)
				(justify mirror)
			)
		)
		(duplicate_pad_numbers_are_jumpers no)
		(fp_rect
			(start 0.7239 1.9939)
			(end -0.7239 -0.2159)
			(stroke
				(width 0)
				(type default)
			)
			(fill no)
			(layer "B.CrtYd")
		)
		(fp_line
			(start 0.7239 -0.2159)
			(end 0.7239 1.9939)
			(stroke
				(width 0.1)
				(type default)
			)
			(layer "B.Fab")
		)
		(fp_line
			(start -0.7239 -0.2159)
			(end 0.7239 -0.2159)
			(stroke
				(width 0.1)
				(type default)
			)
			(layer "B.Fab")
		)
		(fp_line
			(start 0.7239 1.9939)
			(end -0.7239 1.9939)
			(stroke
				(width 0.1)
				(type default)
			)
			(layer "B.Fab")
		)
		(fp_line
			(start -0.7239 1.9939)
			(end -0.7239 -0.2159)
			(stroke
				(width 0.1)
				(type default)
			)
			(layer "B.Fab")
		)
		(pad "1" smd rect
			(at 0 0 270)
			(size 1.27 1.016)
			(layers "B.Cu" "B.Mask" "B.Paste")
			(net "PVDDQ_DEF")
		)
		(pad "2" smd rect
			(at 0 1.778 270)
			(size 1.27 1.016)
			(layers "B.Cu" "B.Mask" "B.Paste")
			(net "GND")
		)
		(zone
			(layer "B.Cu")
			(hatch none 0.5)
			(connect_pads
				(clearance 0)
			)
			(min_thickness 0.25)
			(keepout
				(tracks not_allowed)
				(vias allowed)
				(pads allowed)
				(copperpour not_allowed)
				(footprints allowed)
			)
			(placement
				(enabled no)
				(sheetname "")
			)
			(fill
				(thermal_gap 0.5)
				(thermal_bridge_width 0.5)
				(island_removal_mode 0)
			)
			(polygon
				(pts
					(xy 274.201128 -157.595824) (xy 273.439128 -157.595824) (xy 273.439128 -156.325824) (xy 274.201128 -156.325824)
				)
			)
		)
	)
	(footprint ""
		(layer "B.Cu")
		(at 23.114 -81.534)
		(property "Reference" "R9P33"
			(at 0 0 0)
			(layer "B.SilkS")
			(hide yes)
			(effects
				(font
					(size 1.27 1.27)
				)
				(justify mirror)
			)
		)
		(property "Value" ""
			(at 0 0 0)
			(layer "B.Fab")
			(effects
				(font
					(size 1.27 1.27)
				)
				(justify mirror)
			)
		)
		(duplicate_pad_numbers_are_jumpers no)
		(fp_poly
			(pts
				(xy 0.2794 -0.1016) (xy -0.2794 -0.1016) (xy -0.2794 0.9906) (xy 0.2794 0.9906)
			)
			(stroke
				(width 0)
				(type default)
			)
			(fill no)
			(layer "B.CrtYd")
		)
		(fp_line
			(start -0.2794 -0.1016)
			(end 0.2794 -0.1016)
			(stroke
				(width 0.1)
				(type default)
			)
			(layer "B.Fab")
		)
		(fp_line
			(start -0.2794 0.9906)
			(end -0.2794 -0.1016)
			(stroke
				(width 0.1)
				(type default)
			)
			(layer "B.Fab")
		)
		(fp_line
			(start 0.2794 -0.1016)
			(end 0.2794 0.9906)
			(stroke
				(width 0.1)
				(type default)
			)
			(layer "B.Fab")
		)
		(fp_line
			(start 0.2794 0.9906)
			(end -0.2794 0.9906)
			(stroke
				(width 0.1)
				(type default)
			)
			(layer "B.Fab")
		)
		(pad "1" smd rect
			(at 0 0 180)
			(size 0.508 0.508)
			(layers "B.Cu" "B.Mask" "B.Paste")
			(net "P12V_STBY")
		)
		(pad "2" smd rect
			(at 0 0.889 180)
			(size 0.508 0.508)
			(layers "B.Cu" "B.Mask" "B.Paste")
			(net "A_HSC_INAP")
		)
		(zone
			(layer "B.Cu")
			(hatch none 0.5)
			(connect_pads
				(clearance 0)
			)
			(min_thickness 0.25)
			(keepout
				(tracks allowed)
				(vias not_allowed)
				(pads allowed)
				(copperpour not_allowed)
				(footprints allowed)
			)
			(placement
				(enabled no)
				(sheetname "")
			)
			(fill
				(thermal_gap 0.5)
				(thermal_bridge_width 0.5)
				(island_removal_mode 0)
			)
			(polygon
				(pts
					(xy 23.368 -81.28) (xy 22.86 -81.28) (xy 22.86 -80.899) (xy 23.368 -80.899)
				)
			)
		)
		(zone
			(layer "B.Cu")
			(hatch none 0.5)
			(connect_pads
				(clearance 0)
			)
			(min_thickness 0.25)
			(keepout
				(tracks not_allowed)
				(vias allowed)
				(pads allowed)
				(copperpour not_allowed)
				(footprints allowed)
			)
			(placement
				(enabled no)
				(sheetname "")
			)
			(fill
				(thermal_gap 0.5)
				(thermal_bridge_width 0.5)
				(island_removal_mode 0)
			)
			(polygon
				(pts
					(xy 23.368 -80.899) (xy 22.86 -80.899) (xy 22.86 -81.28) (xy 23.368 -81.28)
				)
			)
		)
	)
	(footprint ""
		(layer "B.Cu")
		(at 459.6384 -52.457858)
		(property "Reference" "C1R4"
			(at 0 0 0)
			(layer "B.SilkS")
			(hide yes)
			(effects
				(font
					(size 1.27 1.27)
				)
				(justify mirror)
			)
		)
		(property "Value" ""
			(at 0 0 0)
			(layer "B.Fab")
			(effects
				(font
					(size 1.27 1.27)
				)
				(justify mirror)
			)
		)
		(duplicate_pad_numbers_are_jumpers no)
		(fp_poly
			(pts
				(xy -0.3048 -0.1016) (xy -0.3048 0.9906) (xy 0.3048 0.9906) (xy 0.3048 -0.1016)
			)
			(stroke
				(width 0)
				(type default)
			)
			(fill no)
			(layer "B.CrtYd")
		)
		(fp_line
			(start -0.3048 -0.1016)
			(end 0.3048 -0.1016)
			(stroke
				(width 0.1)
				(type default)
			)
			(layer "B.Fab")
		)
		(fp_line
			(start -0.3048 0.9906)
			(end -0.3048 -0.1016)
			(stroke
				(width 0.1)
				(type default)
			)
			(layer "B.Fab")
		)
		(fp_line
			(start 0.3048 -0.1016)
			(end 0.3048 0.9906)
			(stroke
				(width 0.1)
				(type default)
			)
			(layer "B.Fab")
		)
		(fp_line
			(start 0.3048 0.9906)
			(end -0.3048 0.9906)
			(stroke
				(width 0.1)
				(type default)
			)
			(layer "B.Fab")
		)
		(pad "1" smd rect
			(at 0 0 180)
			(size 0.508 0.508)
			(layers "B.Cu" "B.Mask" "B.Paste")
			(net "P3E_CPU0_PE3_OCP_TXP<1>")
		)
		(pad "2" smd rect
			(at 0 0.889 180)
			(size 0.508 0.508)
			(layers "B.Cu" "B.Mask" "B.Paste")
			(net "P3E_OCP_CPU0_PE3_C_TXP<1>")
		)
		(zone
			(layer "B.Cu")
			(hatch none 0.5)
			(connect_pads
				(clearance 0)
			)
			(min_thickness 0.25)
			(keepout
				(tracks allowed)
				(vias not_allowed)
				(pads allowed)
				(copperpour not_allowed)
				(footprints allowed)
			)
			(placement
				(enabled no)
				(sheetname "")
			)
			(fill
				(thermal_gap 0.5)
				(thermal_bridge_width 0.5)
				(island_removal_mode 0)
			)
			(polygon
				(pts
					(xy 459.8924 -52.203858) (xy 459.3844 -52.203858) (xy 459.3844 -51.822858) (xy 459.8924 -51.822858)
				)
			)
		)
		(zone
			(layer "B.Cu")
			(hatch none 0.5)
			(connect_pads
				(clearance 0)
			)
			(min_thickness 0.25)
			(keepout
				(tracks not_allowed)
				(vias allowed)
				(pads allowed)
				(copperpour not_allowed)
				(footprints allowed)
			)
			(placement
				(enabled no)
				(sheetname "")
			)
			(fill
				(thermal_gap 0.5)
				(thermal_bridge_width 0.5)
				(island_removal_mode 0)
			)
			(polygon
				(pts
					(xy 459.8924 -51.822858) (xy 459.3844 -51.822858) (xy 459.3844 -52.203858) (xy 459.8924 -52.203858)
				)
			)
		)
	)
)
